# T6G (Grand Teton) — schematic netlist excerpt (pin names and nets, part order shuffled) for the footprints in the layout excerpt that follows; sources: Cadence DE-HDL packaged netlist, KiCad conversion of 04192023_DAF0TMB3IC0_F0TG_MB_C_brd_V02_OCP.brd

C2467  Q_CAP  22UF 4V 20% X6S  pkg C0402  page 74 : A = PVDDCR_SOC_P1 ; B = GND
C789  Q_CAP  0.1UF 10V 10% X7S  pkg C0201  page 301 : A = P0V9_CPU0_RT_2D ; B = GND
C316  Q_CAP  0.1UF 10V 10% X7S  pkg C0201  page 334 : A = P0V9_CPU1_RT1_2A_2D ; B = GND

(kicad_pcb
	(version 20260206)
	(generator "pcbnew")
	(generator_version "10.0")
	(general
		(thickness 1.6)
		(legacy_teardrops no)
	)
	(paper "A4")
	(title_block
		(title "04192023_DAF0TMB3IC0_F0TG_MB_C_brd_V02_OCP.brd")
		(comment 1 "Grand Teton / footprints 8334-8336 of 8354")
	)
	(layers
		(0 "F.Cu" signal "TOP")
		(4 "In1.Cu" signal "GND")
		(6 "In2.Cu" signal "IN1")
		(8 "In3.Cu" signal "GND1")
		(10 "In4.Cu" signal "IN2")
		(12 "In5.Cu" signal "GND2")
		(14 "In6.Cu" signal "IN3")
		(16 "In7.Cu" signal "GND3")
		(18 "In8.Cu" signal "VCC")
		(20 "In9.Cu" signal "VCC1")
		(22 "In10.Cu" signal "GND4")
		(24 "In11.Cu" signal "IN4")
		(26 "In12.Cu" signal "GND5")
		(28 "In13.Cu" signal "IN5")
		(30 "In14.Cu" signal "GND6")
		(32 "In15.Cu" signal "IN6")
		(34 "In16.Cu" signal "GND7")
		(2 "B.Cu" signal "BOTTOM")
		(9 "F.Adhes" user "F.Adhesive")
		(11 "B.Adhes" user "B.Adhesive")
		(13 "F.Paste" user "Package Geometry/Pastemask Top")
		(15 "B.Paste" user "Package Geometry/Pastemask Bottom")
		(5 "F.SilkS" user "Ref Des/Silkscreen Top")
		(7 "B.SilkS" user "Ref Des/Silkscreen Bottom")
		(1 "F.Mask" user "Board Geometry/Soldermask Top")
		(3 "B.Mask" user "Board Geometry/Soldermask Bottom")
		(17 "Dwgs.User" user "User.Drawings")
		(19 "Cmts.User" user "User.Comments")
		(21 "Eco1.User" user "User.Eco1")
		(23 "Eco2.User" user "User.Eco2")
		(25 "Edge.Cuts" user "Board Geometry/Outline")
		(27 "Margin" user)
		(31 "F.CrtYd" user "Package Geometry/Place Bound Top")
		(29 "B.CrtYd" user "Package Geometry/Place Bound Bottom")
		(35 "F.Fab" user "Ref Des/Assembly Top")
		(33 "B.Fab" user "Ref Des/Assembly Bottom")
	)
	(footprint ""
		(layer "B.Cu")
		(at 103.672386 -261.179564 180)
		(property "Reference" "C2467"
			(at 0 0 0)
			(layer "B.SilkS")
			(hide yes)
			(effects
				(font
					(size 1.27 1.27)
				)
				(justify mirror)
			)
		)
		(property "Value" ""
			(at 0 0 0)
			(layer "B.Fab")
			(effects
				(font
					(size 1.27 1.27)
				)
				(justify mirror)
			)
		)
		(duplicate_pad_numbers_are_jumpers no)
		(fp_line
			(start 0.7874 0.4064)
			(end 0.7874 -0.4064)
			(stroke
				(width 0.1524)
				(type default)
			)
			(layer "B.SilkS")
		)
		(fp_line
			(start 0.7874 -0.4064)
			(end -0.7874 -0.4064)
			(stroke
				(width 0.1524)
				(type default)
			)
			(layer "B.SilkS")
		)
		(fp_line
			(start -0.7874 0.4064)
			(end 0.7874 0.4064)
			(stroke
				(width 0.1524)
				(type default)
			)
			(layer "B.SilkS")
		)
		(fp_line
			(start -0.7874 -0.4064)
			(end -0.7874 0.4064)
			(stroke
				(width 0.1524)
				(type default)
			)
			(layer "B.SilkS")
		)
		(fp_line
			(start 0.67945 0.3048)
			(end 0.67945 -0.305054)
			(stroke
				(width 0.1)
				(type default)
			)
			(layer "B.Fab")
		)
		(fp_line
			(start 0.67945 -0.305054)
			(end 0.12065 -0.305054)
			(stroke
				(width 0.1)
				(type default)
			)
			(layer "B.Fab")
		)
		(fp_line
			(start 0.12065 0.3048)
			(end 0.67945 0.3048)
			(stroke
				(width 0.1)
				(type default)
			)
			(layer "B.Fab")
		)
		(fp_line
			(start 0.12065 0.2794)
			(end 0.12065 0.3048)
			(stroke
				(width 0.1)
				(type default)
			)
			(layer "B.Fab")
		)
		(fp_line
			(start 0.12065 -0.2794)
			(end -0.12065 -0.2794)
			(stroke
				(width 0.1)
				(type default)
			)
			(layer "B.Fab")
		)
		(fp_line
			(start 0.12065 -0.305054)
			(end 0.12065 -0.2794)
			(stroke
				(width 0.1)
				(type default)
			)
			(layer "B.Fab")
		)
		(fp_line
			(start -0.120396 0.3048)
			(end -0.120396 0.2794)
			(stroke
				(width 0.1)
				(type default)
			)
			(layer "B.Fab")
		)
		(fp_line
			(start -0.120396 0.2794)
			(end 0.12065 0.2794)
			(stroke
				(width 0.1)
				(type default)
			)
			(layer "B.Fab")
		)
		(fp_line
			(start -0.12065 -0.2794)
			(end -0.12065 -0.3048)
			(stroke
				(width 0.1)
				(type default)
			)
			(layer "B.Fab")
		)
		(fp_line
			(start -0.12065 -0.3048)
			(end -0.67945 -0.3048)
			(stroke
				(width 0.1)
				(type default)
			)
			(layer "B.Fab")
		)
		(fp_line
			(start -0.67945 0.3048)
			(end -0.120396 0.3048)
			(stroke
				(width 0.1)
				(type default)
			)
			(layer "B.Fab")
		)
		(fp_line
			(start -0.67945 -0.3048)
			(end -0.67945 0.3048)
			(stroke
				(width 0.1)
				(type default)
			)
			(layer "B.Fab")
		)
		(pad "1" smd circle
			(at 0.40005 0)
			(size 0 0)
			(layers "B.Cu" "B.Mask" "B.Paste")
			(net "PVDDCR_SOC_P1")
		)
		(pad "2" smd circle
			(at -0.40005 0)
			(size 0 0)
			(layers "B.Cu" "B.Mask" "B.Paste")
			(net "GND")
		)
	)
	(footprint ""
		(layer "B.Cu")
		(at 415.006282 -395.148562 90)
		(property "Reference" "C789"
			(at 0 0 90)
			(layer "B.SilkS")
			(hide yes)
			(effects
				(font
					(size 1.27 1.27)
				)
				(justify mirror)
			)
		)
		(property "Value" ""
			(at 0 0 90)
			(layer "B.Fab")
			(effects
				(font
					(size 1.27 1.27)
				)
				(justify mirror)
			)
		)
		(duplicate_pad_numbers_are_jumpers no)
		(fp_line
			(start 0.299974 -0.150114)
			(end -0.299974 -0.150114)
			(stroke
				(width 0.1)
				(type default)
			)
			(layer "B.Fab")
		)
		(fp_line
			(start -0.299974 -0.150114)
			(end -0.299974 0.150114)
			(stroke
				(width 0.1)
				(type default)
			)
			(layer "B.Fab")
		)
		(fp_line
			(start 0.299974 0.150114)
			(end 0.299974 -0.150114)
			(stroke
				(width 0.1)
				(type default)
			)
			(layer "B.Fab")
		)
		(fp_line
			(start -0.299974 0.150114)
			(end 0.299974 0.150114)
			(stroke
				(width 0.1)
				(type default)
			)
			(layer "B.Fab")
		)
		(pad "1" smd rect
			(at 0.2667 0 270)
			(size 0.3048 0.381)
			(layers "B.Cu" "B.Mask" "B.Paste")
			(net "P0V9_CPU0_RT_2D")
		)
		(pad "2" smd rect
			(at -0.2667 0 270)
			(size 0.3048 0.381)
			(layers "B.Cu" "B.Mask" "B.Paste")
			(net "GND")
		)
	)
	(footprint ""
		(layer "B.Cu")
		(at 93.246194 -388.011162 -90)
		(property "Reference" "C316"
			(at 0 0 90)
			(layer "B.SilkS")
			(hide yes)
			(effects
				(font
					(size 1.27 1.27)
				)
				(justify mirror)
			)
		)
		(property "Value" ""
			(at 0 0 90)
			(layer "B.Fab")
			(effects
				(font
					(size 1.27 1.27)
				)
				(justify mirror)
			)
		)
		(duplicate_pad_numbers_are_jumpers no)
		(fp_line
			(start -0.299974 0.150114)
			(end 0.299974 0.150114)
			(stroke
				(width 0.1)
				(type default)
			)
			(layer "B.Fab")
		)
		(fp_line
			(start 0.299974 0.150114)
			(end 0.299974 -0.150114)
			(stroke
				(width 0.1)
				(type default)
			)
			(layer "B.Fab")
		)
		(fp_line
			(start -0.299974 -0.150114)
			(end -0.299974 0.150114)
			(stroke
				(width 0.1)
				(type default)
			)
			(layer "B.Fab")
		)
		(fp_line
			(start 0.299974 -0.150114)
			(end -0.299974 -0.150114)
			(stroke
				(width 0.1)
				(type default)
			)
			(layer "B.Fab")
		)
		(pad "1" smd rect
			(at 0.2667 0 90)
			(size 0.3048 0.381)
			(layers "B.Cu" "B.Mask" "B.Paste")
			(net "P0V9_CPU1_RT1_2A_2D")
		)
		(pad "2" smd rect
			(at -0.2667 0 90)
			(size 0.3048 0.381)
			(layers "B.Cu" "B.Mask" "B.Paste")
			(net "GND")
		)
	)
)
